(kicad_pcb
	(version 20260206)
	(generator "pcbnew")
	(generator_version "10.0")
	(general
		(thickness 1.6)
		(legacy_teardrops no)
	)
	(paper "A4")
	(title_block
		(title "03242023_DA0F0TMBIJ0_F0T_Motherboard_J_brd_V01_OCP.brd")
		(comment 1 "Grand Teton / footprints 4865-4870 of 6105")
	)
	(layers
		(0 "F.Cu" signal "TOP")
		(4 "In1.Cu" signal "GND")
		(6 "In2.Cu" signal "IN1")
		(8 "In3.Cu" signal "GND1")
		(10 "In4.Cu" signal "IN2")
		(12 "In5.Cu" signal "GND2")
		(14 "In6.Cu" signal "IN3")
		(16 "In7.Cu" signal "GND3")
		(18 "In8.Cu" signal "VCC")
		(20 "In9.Cu" signal "VCC1")
		(22 "In10.Cu" signal "GND4")
		(24 "In11.Cu" signal "IN4")
		(26 "In12.Cu" signal "GND5")
		(28 "In13.Cu" signal "IN5")
		(30 "In14.Cu" signal "GND6")
		(32 "In15.Cu" signal "IN6")
		(34 "In16.Cu" signal "GND7")
		(2 "B.Cu" signal "BOTTOM")
		(9 "F.Adhes" user "F.Adhesive")
		(11 "B.Adhes" user "B.Adhesive")
		(13 "F.Paste" user "Package Geometry/Pastemask Top")
		(15 "B.Paste" user "Package Geometry/Pastemask Bottom")
		(5 "F.SilkS" user "Ref Des/Silkscreen Top")
		(7 "B.SilkS" user "Ref Des/Silkscreen Bottom")
		(1 "F.Mask" user "Board Geometry/Soldermask Top")
		(3 "B.Mask" user "Board Geometry/Soldermask Bottom")
		(17 "Dwgs.User" user "User.Drawings")
		(19 "Cmts.User" user "User.Comments")
		(21 "Eco1.User" user "User.Eco1")
		(23 "Eco2.User" user "User.Eco2")
		(25 "Edge.Cuts" user "Board Geometry/Outline")
		(27 "Margin" user)
		(31 "F.CrtYd" user "Package Geometry/Place Bound Top")
		(29 "B.CrtYd" user "Package Geometry/Place Bound Bottom")
		(35 "F.Fab" user "Ref Des/Assembly Top")
		(33 "B.Fab" user "Ref Des/Assembly Bottom")
	)
	(footprint ""
		(layer "B.Cu")
		(at 244.20703 -97.219516 -90)
		(property "Reference" "C112"
			(at 0 0 90)
			(layer "B.SilkS")
			(hide yes)
			(effects
				(font
					(size 1.27 1.27)
				)
				(justify mirror)
			)
		)
		(property "Value" ""
			(at 0 0 90)
			(layer "B.Fab")
			(effects
				(font
					(size 1.27 1.27)
				)
				(justify mirror)
			)
		)
		(duplicate_pad_numbers_are_jumpers no)
		(fp_line
			(start -0.7874 0.4064)
			(end 0.7874 0.4064)
			(stroke
				(width 0.1524)
				(type default)
			)
			(layer "B.SilkS")
		)
		(fp_line
			(start 0.7874 0.4064)
			(end 0.7874 -0.4064)
			(stroke
				(width 0.1524)
				(type default)
			)
			(layer "B.SilkS")
		)
		(fp_line
			(start -0.7874 -0.4064)
			(end -0.7874 0.4064)
			(stroke
				(width 0.1524)
				(type default)
			)
			(layer "B.SilkS")
		)
		(fp_line
			(start 0.7874 -0.4064)
			(end -0.7874 -0.4064)
			(stroke
				(width 0.1524)
				(type default)
			)
			(layer "B.SilkS")
		)
		(fp_line
			(start -0.67945 0.3048)
			(end -0.120396 0.3048)
			(stroke
				(width 0.1)
				(type default)
			)
			(layer "B.Fab")
		)
		(fp_line
			(start -0.120396 0.3048)
			(end -0.120396 0.2794)
			(stroke
				(width 0.1)
				(type default)
			)
			(layer "B.Fab")
		)
		(fp_line
			(start 0.12065 0.3048)
			(end 0.67945 0.3048)
			(stroke
				(width 0.1)
				(type default)
			)
			(layer "B.Fab")
		)
		(fp_line
			(start 0.67945 0.3048)
			(end 0.67945 -0.305054)
			(stroke
				(width 0.1)
				(type default)
			)
			(layer "B.Fab")
		)
		(fp_line
			(start -0.120396 0.2794)
			(end 0.12065 0.2794)
			(stroke
				(width 0.1)
				(type default)
			)
			(layer "B.Fab")
		)
		(fp_line
			(start 0.12065 0.2794)
			(end 0.12065 0.3048)
			(stroke
				(width 0.1)
				(type default)
			)
			(layer "B.Fab")
		)
		(fp_line
			(start -0.12065 -0.2794)
			(end -0.12065 -0.3048)
			(stroke
				(width 0.1)
				(type default)
			)
			(layer "B.Fab")
		)
		(fp_line
			(start 0.12065 -0.2794)
			(end -0.12065 -0.2794)
			(stroke
				(width 0.1)
				(type default)
			)
			(layer "B.Fab")
		)
		(fp_line
			(start -0.67945 -0.3048)
			(end -0.67945 0.3048)
			(stroke
				(width 0.1)
				(type default)
			)
			(layer "B.Fab")
		)
		(fp_line
			(start -0.12065 -0.3048)
			(end -0.67945 -0.3048)
			(stroke
				(width 0.1)
				(type default)
			)
			(layer "B.Fab")
		)
		(fp_line
			(start 0.12065 -0.305054)
			(end 0.12065 -0.2794)
			(stroke
				(width 0.1)
				(type default)
			)
			(layer "B.Fab")
		)
		(fp_line
			(start 0.67945 -0.305054)
			(end 0.12065 -0.305054)
			(stroke
				(width 0.1)
				(type default)
			)
			(layer "B.Fab")
		)
		(pad "1" smd circle
			(at 0.40005 0 90)
			(size 0 0)
			(layers "B.Cu" "B.Mask" "B.Paste")
			(net "P3V3_AUX_CLK_GEN_VDDXTAL_CK440")
		)
		(pad "2" smd circle
			(at -0.40005 0 90)
			(size 0 0)
			(layers "B.Cu" "B.Mask" "B.Paste")
			(net "GND")
		)
	)
	(footprint ""
		(layer "B.Cu")
		(at 185.691526 -312.982864 90)
		(property "Reference" "R2504"
			(at 0 0 90)
			(layer "B.SilkS")
			(hide yes)
			(effects
				(font
					(size 1.27 1.27)
				)
				(justify mirror)
			)
		)
		(property "Value" ""
			(at 0 0 90)
			(layer "B.Fab")
			(effects
				(font
					(size 1.27 1.27)
				)
				(justify mirror)
			)
		)
		(duplicate_pad_numbers_are_jumpers no)
		(fp_line
			(start 0.7874 -0.4064)
			(end -0.7874 -0.4064)
			(stroke
				(width 0.1524)
				(type default)
			)
			(layer "B.SilkS")
		)
		(fp_line
			(start -0.7874 -0.4064)
			(end -0.7874 0.4064)
			(stroke
				(width 0.1524)
				(type default)
			)
			(layer "B.SilkS")
		)
		(fp_line
			(start 0.7874 0.4064)
			(end 0.7874 -0.4064)
			(stroke
				(width 0.1524)
				(type default)
			)
			(layer "B.SilkS")
		)
		(fp_line
			(start -0.7874 0.4064)
			(end 0.7874 0.4064)
			(stroke
				(width 0.1524)
				(type default)
			)
			(layer "B.SilkS")
		)
		(fp_line
			(start 0.67945 -0.305054)
			(end 0.12065 -0.305054)
			(stroke
				(width 0.1)
				(type default)
			)
			(layer "B.Fab")
		)
		(fp_line
			(start 0.12065 -0.305054)
			(end 0.12065 -0.2794)
			(stroke
				(width 0.1)
				(type default)
			)
			(layer "B.Fab")
		)
		(fp_line
			(start -0.12065 -0.3048)
			(end -0.67945 -0.3048)
			(stroke
				(width 0.1)
				(type default)
			)
			(layer "B.Fab")
		)
		(fp_line
			(start -0.67945 -0.3048)
			(end -0.67945 0.3048)
			(stroke
				(width 0.1)
				(type default)
			)
			(layer "B.Fab")
		)
		(fp_line
			(start 0.12065 -0.2794)
			(end -0.12065 -0.2794)
			(stroke
				(width 0.1)
				(type default)
			)
			(layer "B.Fab")
		)
		(fp_line
			(start -0.12065 -0.2794)
			(end -0.12065 -0.3048)
			(stroke
				(width 0.1)
				(type default)
			)
			(layer "B.Fab")
		)
		(fp_line
			(start 0.12065 0.2794)
			(end 0.12065 0.3048)
			(stroke
				(width 0.1)
				(type default)
			)
			(layer "B.Fab")
		)
		(fp_line
			(start -0.120396 0.2794)
			(end 0.12065 0.2794)
			(stroke
				(width 0.1)
				(type default)
			)
			(layer "B.Fab")
		)
		(fp_line
			(start 0.67945 0.3048)
			(end 0.67945 -0.305054)
			(stroke
				(width 0.1)
				(type default)
			)
			(layer "B.Fab")
		)
		(fp_line
			(start 0.12065 0.3048)
			(end 0.67945 0.3048)
			(stroke
				(width 0.1)
				(type default)
			)
			(layer "B.Fab")
		)
		(fp_line
			(start -0.120396 0.3048)
			(end -0.120396 0.2794)
			(stroke
				(width 0.1)
				(type default)
			)
			(layer "B.Fab")
		)
		(fp_line
			(start -0.67945 0.3048)
			(end -0.120396 0.3048)
			(stroke
				(width 0.1)
				(type default)
			)
			(layer "B.Fab")
		)
		(pad "1" smd circle
			(at 0.40005 0 270)
			(size 0 0)
			(layers "B.Cu" "B.Mask" "B.Paste")
			(net "PWRGD_FAIL_CPU1_EF_R1")
		)
		(pad "2" smd circle
			(at -0.40005 0 270)
			(size 0 0)
			(layers "B.Cu" "B.Mask" "B.Paste")
			(net "PWRGD_FAIL_CPU1_EF_R")
		)
	)
	(footprint ""
		(layer "B.Cu")
		(at 174.155608 -105.375456 90)
		(property "Reference" "C1913"
			(at 0 0 90)
			(layer "B.SilkS")
			(hide yes)
			(effects
				(font
					(size 1.27 1.27)
				)
				(justify mirror)
			)
		)
		(property "Value" ""
			(at 0 0 90)
			(layer "B.Fab")
			(effects
				(font
					(size 1.27 1.27)
				)
				(justify mirror)
			)
		)
		(duplicate_pad_numbers_are_jumpers no)
		(fp_line
			(start 0.69215 -0.2921)
			(end -0.69215 -0.2921)
			(stroke
				(width 0.1524)
				(type default)
			)
			(layer "B.SilkS")
		)
		(fp_line
			(start -0.69215 -0.2921)
			(end -0.69215 0.2921)
			(stroke
				(width 0.1524)
				(type default)
			)
			(layer "B.SilkS")
		)
		(fp_line
			(start 0.69215 0.2921)
			(end 0.69215 -0.2921)
			(stroke
				(width 0.1524)
				(type default)
			)
			(layer "B.SilkS")
		)
		(fp_line
			(start -0.69215 0.2921)
			(end 0.69215 0.2921)
			(stroke
				(width 0.1524)
				(type default)
			)
			(layer "B.SilkS")
		)
		(fp_line
			(start 0.51435 -0.2794)
			(end -0.51435 -0.2794)
			(stroke
				(width 0.1)
				(type default)
			)
			(layer "B.Fab")
		)
		(fp_line
			(start -0.51435 -0.2794)
			(end -0.51435 0.2794)
			(stroke
				(width 0.1)
				(type default)
			)
			(layer "B.Fab")
		)
		(fp_line
			(start 0.51435 0.2794)
			(end 0.51435 -0.2794)
			(stroke
				(width 0.1)
				(type default)
			)
			(layer "B.Fab")
		)
		(fp_line
			(start -0.51435 0.2794)
			(end 0.51435 0.2794)
			(stroke
				(width 0.1)
				(type default)
			)
			(layer "B.Fab")
		)
		(pad "1" smd circle
			(at 0.40005 0 270)
			(size 0 0)
			(layers "B.Cu" "B.Mask" "B.Paste")
			(net "P3V3_AUX_FPGA_VCCIO5")
		)
		(pad "2" smd circle
			(at -0.40005 0 270)
			(size 0 0)
			(layers "B.Cu" "B.Mask" "B.Paste")
			(net "GND")
		)
		(zone
			(layer "B.Cu")
			(hatch none 0.5)
			(connect_pads
				(clearance 0)
			)
			(min_thickness 0.25)
			(keepout
				(tracks not_allowed)
				(vias allowed)
				(pads allowed)
				(copperpour not_allowed)
				(footprints allowed)
			)
			(placement
				(enabled no)
				(sheetname "")
			)
			(fill
				(thermal_gap 0.5)
				(thermal_bridge_width 0.5)
				(island_removal_mode 0)
			)
			(polygon
				(pts
					(xy 174.243238 -105.565956) (xy 174.301404 -105.474516) (xy 174.301404 -105.275126) (xy 174.243238 -105.184956)
					(xy 174.067978 -105.184956) (xy 174.009558 -105.275126) (xy 174.009558 -105.474516) (xy 174.067724 -105.565956)
				)
			)
		)
	)
	(footprint ""
		(layer "B.Cu")
		(at 482.66985 -184.609232 90)
		(property "Reference" "X45"
			(at -2.237232 4.72948 270)
			(unlocked yes)
			(layer "B.SilkS")
			(effects
				(font
					(size 0.7874 0.5842)
					(thickness 0.1524)
				)
				(justify left mirror)
			)
		)
		(property "Value" ""
			(at 0 0 90)
			(layer "B.Fab")
			(effects
				(font
					(size 1.27 1.27)
				)
				(justify mirror)
			)
		)
		(property "Device Type" "TP_TDR_4P_FTS_TH-TP_TDR_4P_DIPA"
			(at -1.30175 1.27 0)
			(unlocked yes)
			(layer "B.Fab")
			(hide yes)
			(effects
				(font
					(size 0.635 0.4064)
					(thickness 0.1524)
				)
				(justify mirror)
			)
		)
		(property "User Part Number" "N_A"
			(at -1.30175 1.27 0)
			(unlocked yes)
			(layer "Cmts.User")
			(hide yes)
			(effects
				(font
					(size 0.635 0.4064)
					(thickness 0.1524)
				)
				(justify mirror)
			)
		)
		(duplicate_pad_numbers_are_jumpers no)
		(fp_line
			(start 0 -1.27)
			(end 0 -0.635)
			(stroke
				(width 0.1524)
				(type default)
			)
			(layer "B.SilkS")
		)
		(fp_line
			(start -2.54 -1.27)
			(end 0 -1.27)
			(stroke
				(width 0.1524)
				(type default)
			)
			(layer "B.SilkS")
		)
		(fp_line
			(start -2.54 -1.1303)
			(end -2.54 -1.27)
			(stroke
				(width 0.1524)
				(type default)
			)
			(layer "B.SilkS")
		)
		(fp_line
			(start 0 0.635)
			(end 0 1.905)
			(stroke
				(width 0.1524)
				(type default)
			)
			(layer "B.SilkS")
		)
		(fp_line
			(start -2.54 1.4097)
			(end -2.54 1.1303)
			(stroke
				(width 0.1524)
				(type default)
			)
			(layer "B.SilkS")
		)
		(fp_line
			(start 0 3.175)
			(end 0 3.81)
			(stroke
				(width 0.1524)
				(type default)
			)
			(layer "B.SilkS")
		)
		(fp_line
			(start 0 3.81)
			(end -2.54 3.81)
			(stroke
				(width 0.1524)
				(type default)
			)
			(layer "B.SilkS")
		)
		(fp_line
			(start -2.54 3.81)
			(end -2.54 3.6703)
			(stroke
				(width 0.1524)
				(type default)
			)
			(layer "B.SilkS")
		)
		(fp_poly
			(pts
				(xy 0.761746 0) (xy 2.285746 -0.762) (xy 2.285746 0.762)
			)
			(stroke
				(width 0)
				(type default)
			)
			(fill yes)
			(layer "B.SilkS")
		)
		(fp_line
			(start 0 -1.27)
			(end 0 3.81)
			(stroke
				(width 0.1)
				(type default)
			)
			(layer "B.Fab")
		)
		(fp_line
			(start -2.54 -1.27)
			(end 0 -1.27)
			(stroke
				(width 0.1)
				(type default)
			)
			(layer "B.Fab")
		)
		(fp_line
			(start 0 3.81)
			(end -2.54 3.81)
			(stroke
				(width 0.1)
				(type default)
			)
			(layer "B.Fab")
		)
		(fp_line
			(start -2.54 3.81)
			(end -2.54 -1.27)
			(stroke
				(width 0.1)
				(type default)
			)
			(layer "B.Fab")
		)
		(fp_poly
			(pts
				(xy 0.761746 0) (xy 2.285746 -0.762) (xy 2.285746 0.762)
			)
			(stroke
				(width 0)
				(type default)
			)
			(fill yes)
			(layer "B.Fab")
		)
		(pad "1" thru_hole circle
			(at 0 0 270)
			(size 1.0033 1.0033)
			(drill 0.249936)
			(layers "*.Cu" "*.Mask")
			(remove_unused_layers no)
			(net "TDR_DIFF_85_NECK_IN4_DN")
			(clearance 0.10795)
			(padstack
				(mode front_inner_back)
				(layer "Inner"
					(shape circle)
					(size 0.8001 0.8001)
					(clearance 0.1524)
				)
				(layer "B.Cu"
					(shape circle)
					(size 1.0033 1.0033)
					(thermal_gap 0.10795)
					(clearance 0.10795)
				)
			)
		)
		(pad "2" thru_hole circle
			(at -2.54 0 270)
			(size 1.9939 1.9939)
			(drill 0.249936)
			(layers "*.Cu" "*.Mask")
			(remove_unused_layers no)
			(net "T1_GND")
			(clearance 0.10795)
			(padstack
				(mode front_inner_back)
				(layer "Inner"
					(shape circle)
					(size 0.8001 0.8001)
					(clearance 0.1524)
				)
				(layer "B.Cu"
					(shape circle)
					(size 1.9939 1.9939)
					(thermal_gap 0.10795)
					(clearance 0.10795)
				)
			)
		)
		(pad "3" thru_hole circle
			(at -2.54 2.54 270)
			(size 1.9939 1.9939)
			(drill 0.249936)
			(layers "*.Cu" "*.Mask")
			(remove_unused_layers no)
			(net "T1_GND")
			(clearance 0.10795)
			(padstack
				(mode front_inner_back)
				(layer "Inner"
					(shape circle)
					(size 0.8001 0.8001)
					(clearance 0.1524)
				)
				(layer "B.Cu"
					(shape circle)
					(size 1.9939 1.9939)
					(thermal_gap 0.10795)
					(clearance 0.10795)
				)
			)
		)
		(pad "4" thru_hole circle
			(at 0 2.54 270)
			(size 1.0033 1.0033)
			(drill 0.249936)
			(layers "*.Cu" "*.Mask")
			(remove_unused_layers no)
			(net "TDR_DIFF_85_NECK_IN4_DP")
			(clearance 0.10795)
			(padstack
				(mode front_inner_back)
				(layer "Inner"
					(shape circle)
					(size 0.8001 0.8001)
					(clearance 0.1524)
				)
				(layer "B.Cu"
					(shape circle)
					(size 1.0033 1.0033)
					(thermal_gap 0.10795)
					(clearance 0.10795)
				)
			)
		)
	)
	(footprint ""
		(layer "B.Cu")
		(at 168.133268 -356.42169 -90)
		(property "Reference" "PR1331"
			(at 0 0 90)
			(layer "B.SilkS")
			(hide yes)
			(effects
				(font
					(size 1.27 1.27)
				)
				(justify mirror)
			)
		)
		(property "Value" ""
			(at 0 0 90)
			(layer "B.Fab")
			(effects
				(font
					(size 1.27 1.27)
				)
				(justify mirror)
			)
		)
		(duplicate_pad_numbers_are_jumpers no)
		(fp_line
			(start -0.7874 0.4064)
			(end 0.7874 0.4064)
			(stroke
				(width 0.1524)
				(type default)
			)
			(layer "B.SilkS")
		)
		(fp_line
			(start 0.7874 0.4064)
			(end 0.7874 -0.4064)
			(stroke
				(width 0.1524)
				(type default)
			)
			(layer "B.SilkS")
		)
		(fp_line
			(start -0.7874 -0.4064)
			(end -0.7874 0.4064)
			(stroke
				(width 0.1524)
				(type default)
			)
			(layer "B.SilkS")
		)
		(fp_line
			(start 0.7874 -0.4064)
			(end -0.7874 -0.4064)
			(stroke
				(width 0.1524)
				(type default)
			)
			(layer "B.SilkS")
		)
		(fp_line
			(start -0.67945 0.3048)
			(end -0.120396 0.3048)
			(stroke
				(width 0.1)
				(type default)
			)
			(layer "B.Fab")
		)
		(fp_line
			(start -0.120396 0.3048)
			(end -0.120396 0.2794)
			(stroke
				(width 0.1)
				(type default)
			)
			(layer "B.Fab")
		)
		(fp_line
			(start 0.12065 0.3048)
			(end 0.67945 0.3048)
			(stroke
				(width 0.1)
				(type default)
			)
			(layer "B.Fab")
		)
		(fp_line
			(start 0.67945 0.3048)
			(end 0.67945 -0.305054)
			(stroke
				(width 0.1)
				(type default)
			)
			(layer "B.Fab")
		)
		(fp_line
			(start -0.120396 0.2794)
			(end 0.12065 0.2794)
			(stroke
				(width 0.1)
				(type default)
			)
			(layer "B.Fab")
		)
		(fp_line
			(start 0.12065 0.2794)
			(end 0.12065 0.3048)
			(stroke
				(width 0.1)
				(type default)
			)
			(layer "B.Fab")
		)
		(fp_line
			(start -0.12065 -0.2794)
			(end -0.12065 -0.3048)
			(stroke
				(width 0.1)
				(type default)
			)
			(layer "B.Fab")
		)
		(fp_line
			(start 0.12065 -0.2794)
			(end -0.12065 -0.2794)
			(stroke
				(width 0.1)
				(type default)
			)
			(layer "B.Fab")
		)
		(fp_line
			(start -0.67945 -0.3048)
			(end -0.67945 0.3048)
			(stroke
				(width 0.1)
				(type default)
			)
			(layer "B.Fab")
		)
		(fp_line
			(start -0.12065 -0.3048)
			(end -0.67945 -0.3048)
			(stroke
				(width 0.1)
				(type default)
			)
			(layer "B.Fab")
		)
		(fp_line
			(start 0.12065 -0.305054)
			(end 0.12065 -0.2794)
			(stroke
				(width 0.1)
				(type default)
			)
			(layer "B.Fab")
		)
		(fp_line
			(start 0.67945 -0.305054)
			(end 0.12065 -0.305054)
			(stroke
				(width 0.1)
				(type default)
			)
			(layer "B.Fab")
		)
		(pad "1" smd circle
			(at 0.40005 0 90)
			(size 0 0)
			(layers "B.Cu" "B.Mask" "B.Paste")
			(net "PVCCFA_EHV_FIVRA_CPU1_VOS1")
		)
		(pad "2" smd circle
			(at -0.40005 0 90)
			(size 0 0)
			(layers "B.Cu" "B.Mask" "B.Paste")
			(net "PVCCFA_EHV_FIVRA_CPU1")
		)
	)
	(footprint ""
		(layer "B.Cu")
		(at 286.268414 -321.549776 -90)
		(property "Reference" "C9"
			(at 0 0 90)
			(layer "B.SilkS")
			(hide yes)
			(effects
				(font
					(size 1.27 1.27)
				)
				(justify mirror)
			)
		)
		(property "Value" ""
			(at 0 0 90)
			(layer "B.Fab")
			(effects
				(font
					(size 1.27 1.27)
				)
				(justify mirror)
			)
		)
		(duplicate_pad_numbers_are_jumpers no)
		(fp_line
			(start -1.524 0.762)
			(end 1.524 0.762)
			(stroke
				(width 0.1524)
				(type default)
			)
			(layer "B.SilkS")
		)
		(fp_line
			(start 1.524 0.762)
			(end 1.524 -0.762)
			(stroke
				(width 0.1524)
				(type default)
			)
			(layer "B.SilkS")
		)
		(fp_line
			(start -1.524 -0.762)
			(end -1.524 0.762)
			(stroke
				(width 0.1524)
				(type default)
			)
			(layer "B.SilkS")
		)
		(fp_line
			(start 1.524 -0.762)
			(end -1.524 -0.762)
			(stroke
				(width 0.1524)
				(type default)
			)
			(layer "B.SilkS")
		)
		(fp_line
			(start -1.1049 0.724916)
			(end -1.1049 -0.724916)
			(stroke
				(width 0.1)
				(type default)
			)
			(layer "B.Fab")
		)
		(fp_line
			(start 1.1049 0.724916)
			(end -1.1049 0.724916)
			(stroke
				(width 0.1)
				(type default)
			)
			(layer "B.Fab")
		)
		(fp_line
			(start -1.1049 -0.724916)
			(end 1.1049 -0.724916)
			(stroke
				(width 0.1)
				(type default)
			)
			(layer "B.Fab")
		)
		(fp_line
			(start 1.1049 -0.724916)
			(end 1.1049 0.724916)
			(stroke
				(width 0.1)
				(type default)
			)
			(layer "B.Fab")
		)
		(pad "1" smd rect
			(at 0.889 0 270)
			(size 1.016 1.27)
			(layers "B.Cu" "B.Mask" "B.Paste")
			(net "P12V_S3_AUX_CPU0_NVDIMM")
		)
		(pad "2" smd rect
			(at -0.889 0 270)
			(size 1.016 1.27)
			(layers "B.Cu" "B.Mask" "B.Paste")
			(net "GND")
		)
	)
)
